(kicad_pcb
	(version 20260206)
	(generator "pcbnew")
	(generator_version "10.0")
	(general
		(thickness 1.6)
		(legacy_teardrops no)
	)
	(paper "A4")
	(title_block
		(title "03242023_DA0F0TMBIJ0_F0T_Motherboard_J_brd_V01_OCP.brd")
		(comment 1 "Grand Teton / footprints 3020-3027 of 6105")
	)
	(layers
		(0 "F.Cu" signal "TOP")
		(4 "In1.Cu" signal "GND")
		(6 "In2.Cu" signal "IN1")
		(8 "In3.Cu" signal "GND1")
		(10 "In4.Cu" signal "IN2")
		(12 "In5.Cu" signal "GND2")
		(14 "In6.Cu" signal "IN3")
		(16 "In7.Cu" signal "GND3")
		(18 "In8.Cu" signal "VCC")
		(20 "In9.Cu" signal "VCC1")
		(22 "In10.Cu" signal "GND4")
		(24 "In11.Cu" signal "IN4")
		(26 "In12.Cu" signal "GND5")
		(28 "In13.Cu" signal "IN5")
		(30 "In14.Cu" signal "GND6")
		(32 "In15.Cu" signal "IN6")
		(34 "In16.Cu" signal "GND7")
		(2 "B.Cu" signal "BOTTOM")
		(9 "F.Adhes" user "F.Adhesive")
		(11 "B.Adhes" user "B.Adhesive")
		(13 "F.Paste" user "Package Geometry/Pastemask Top")
		(15 "B.Paste" user "Package Geometry/Pastemask Bottom")
		(5 "F.SilkS" user "Ref Des/Silkscreen Top")
		(7 "B.SilkS" user "Ref Des/Silkscreen Bottom")
		(1 "F.Mask" user "Board Geometry/Soldermask Top")
		(3 "B.Mask" user "Board Geometry/Soldermask Bottom")
		(17 "Dwgs.User" user "User.Drawings")
		(19 "Cmts.User" user "User.Comments")
		(21 "Eco1.User" user "User.Eco1")
		(23 "Eco2.User" user "User.Eco2")
		(25 "Edge.Cuts" user "Board Geometry/Outline")
		(27 "Margin" user)
		(31 "F.CrtYd" user "Package Geometry/Place Bound Top")
		(29 "B.CrtYd" user "Package Geometry/Place Bound Bottom")
		(35 "F.Fab" user "Ref Des/Assembly Top")
		(33 "B.Fab" user "Ref Des/Assembly Bottom")
	)
	(footprint ""
		(layer "F.Cu")
		(at 84.5058 -35.651948 90)
		(property "Reference" "R4616"
			(at 0 0 90)
			(layer "F.SilkS")
			(hide yes)
			(effects
				(font
					(size 1.27 1.27)
				)
			)
		)
		(property "Value" ""
			(at 0 0 90)
			(layer "F.Fab")
			(effects
				(font
					(size 1.27 1.27)
				)
			)
		)
		(duplicate_pad_numbers_are_jumpers no)
		(fp_line
			(start 0.7874 -0.4064)
			(end 0.7874 0.4064)
			(stroke
				(width 0.1524)
				(type default)
			)
			(layer "F.SilkS")
		)
		(fp_line
			(start -0.7874 -0.4064)
			(end 0.7874 -0.4064)
			(stroke
				(width 0.1524)
				(type default)
			)
			(layer "F.SilkS")
		)
		(fp_line
			(start 0.7874 0.4064)
			(end -0.7874 0.4064)
			(stroke
				(width 0.1524)
				(type default)
			)
			(layer "F.SilkS")
		)
		(fp_line
			(start -0.7874 0.4064)
			(end -0.7874 -0.4064)
			(stroke
				(width 0.1524)
				(type default)
			)
			(layer "F.SilkS")
		)
		(fp_line
			(start -0.12065 -0.305054)
			(end -0.12065 -0.2794)
			(stroke
				(width 0.1)
				(type default)
			)
			(layer "F.Fab")
		)
		(fp_line
			(start -0.67945 -0.305054)
			(end -0.12065 -0.305054)
			(stroke
				(width 0.1)
				(type default)
			)
			(layer "F.Fab")
		)
		(fp_line
			(start 0.67945 -0.3048)
			(end 0.67945 0.3048)
			(stroke
				(width 0.1)
				(type default)
			)
			(layer "F.Fab")
		)
		(fp_line
			(start 0.12065 -0.3048)
			(end 0.67945 -0.3048)
			(stroke
				(width 0.1)
				(type default)
			)
			(layer "F.Fab")
		)
		(fp_line
			(start 0.12065 -0.2794)
			(end 0.12065 -0.3048)
			(stroke
				(width 0.1)
				(type default)
			)
			(layer "F.Fab")
		)
		(fp_line
			(start -0.12065 -0.2794)
			(end 0.12065 -0.2794)
			(stroke
				(width 0.1)
				(type default)
			)
			(layer "F.Fab")
		)
		(fp_line
			(start 0.120396 0.2794)
			(end -0.12065 0.2794)
			(stroke
				(width 0.1)
				(type default)
			)
			(layer "F.Fab")
		)
		(fp_line
			(start -0.12065 0.2794)
			(end -0.12065 0.3048)
			(stroke
				(width 0.1)
				(type default)
			)
			(layer "F.Fab")
		)
		(fp_line
			(start 0.67945 0.3048)
			(end 0.120396 0.3048)
			(stroke
				(width 0.1)
				(type default)
			)
			(layer "F.Fab")
		)
		(fp_line
			(start 0.120396 0.3048)
			(end 0.120396 0.2794)
			(stroke
				(width 0.1)
				(type default)
			)
			(layer "F.Fab")
		)
		(fp_line
			(start -0.12065 0.3048)
			(end -0.67945 0.3048)
			(stroke
				(width 0.1)
				(type default)
			)
			(layer "F.Fab")
		)
		(fp_line
			(start -0.67945 0.3048)
			(end -0.67945 -0.305054)
			(stroke
				(width 0.1)
				(type default)
			)
			(layer "F.Fab")
		)
		(pad "1" smd circle
			(at -0.40005 0 90)
			(size 0 0)
			(layers "F.Cu" "F.Mask" "F.Paste")
			(net "HP_OCP_V3_2_RST")
		)
		(pad "2" smd circle
			(at 0.40005 0 90)
			(size 0 0)
			(layers "F.Cu" "F.Mask" "F.Paste")
			(net "HP_OCP_V3_2_RST_R")
		)
	)
	(footprint ""
		(layer "F.Cu")
		(at 104.8258 -408.2796)
		(property "Reference" "R4726"
			(at 0 0 0)
			(layer "F.SilkS")
			(hide yes)
			(effects
				(font
					(size 1.27 1.27)
				)
			)
		)
		(property "Value" ""
			(at 0 0 0)
			(layer "F.Fab")
			(effects
				(font
					(size 1.27 1.27)
				)
			)
		)
		(duplicate_pad_numbers_are_jumpers no)
		(fp_line
			(start -0.7874 -0.4064)
			(end 0.7874 -0.4064)
			(stroke
				(width 0.1524)
				(type default)
			)
			(layer "F.SilkS")
		)
		(fp_line
			(start -0.7874 0.4064)
			(end -0.7874 -0.4064)
			(stroke
				(width 0.1524)
				(type default)
			)
			(layer "F.SilkS")
		)
		(fp_line
			(start 0.7874 -0.4064)
			(end 0.7874 0.4064)
			(stroke
				(width 0.1524)
				(type default)
			)
			(layer "F.SilkS")
		)
		(fp_line
			(start 0.7874 0.4064)
			(end -0.7874 0.4064)
			(stroke
				(width 0.1524)
				(type default)
			)
			(layer "F.SilkS")
		)
		(fp_line
			(start -0.67945 -0.305054)
			(end -0.12065 -0.305054)
			(stroke
				(width 0.1)
				(type default)
			)
			(layer "F.Fab")
		)
		(fp_line
			(start -0.67945 0.3048)
			(end -0.67945 -0.305054)
			(stroke
				(width 0.1)
				(type default)
			)
			(layer "F.Fab")
		)
		(fp_line
			(start -0.12065 -0.305054)
			(end -0.12065 -0.2794)
			(stroke
				(width 0.1)
				(type default)
			)
			(layer "F.Fab")
		)
		(fp_line
			(start -0.12065 -0.2794)
			(end 0.12065 -0.2794)
			(stroke
				(width 0.1)
				(type default)
			)
			(layer "F.Fab")
		)
		(fp_line
			(start -0.12065 0.2794)
			(end -0.12065 0.3048)
			(stroke
				(width 0.1)
				(type default)
			)
			(layer "F.Fab")
		)
		(fp_line
			(start -0.12065 0.3048)
			(end -0.67945 0.3048)
			(stroke
				(width 0.1)
				(type default)
			)
			(layer "F.Fab")
		)
		(fp_line
			(start 0.120396 0.2794)
			(end -0.12065 0.2794)
			(stroke
				(width 0.1)
				(type default)
			)
			(layer "F.Fab")
		)
		(fp_line
			(start 0.120396 0.3048)
			(end 0.120396 0.2794)
			(stroke
				(width 0.1)
				(type default)
			)
			(layer "F.Fab")
		)
		(fp_line
			(start 0.12065 -0.3048)
			(end 0.67945 -0.3048)
			(stroke
				(width 0.1)
				(type default)
			)
			(layer "F.Fab")
		)
		(fp_line
			(start 0.12065 -0.2794)
			(end 0.12065 -0.3048)
			(stroke
				(width 0.1)
				(type default)
			)
			(layer "F.Fab")
		)
		(fp_line
			(start 0.67945 -0.3048)
			(end 0.67945 0.3048)
			(stroke
				(width 0.1)
				(type default)
			)
			(layer "F.Fab")
		)
		(fp_line
			(start 0.67945 0.3048)
			(end 0.120396 0.3048)
			(stroke
				(width 0.1)
				(type default)
			)
			(layer "F.Fab")
		)
		(pad "1" smd circle
			(at -0.40005 0)
			(size 0 0)
			(layers "F.Cu" "F.Mask" "F.Paste")
			(net "P3V3_AUX")
		)
		(pad "2" smd circle
			(at 0.40005 0)
			(size 0 0)
			(layers "F.Cu" "F.Mask" "F.Paste")
			(net "PRSNT_SWB_ISO_N")
		)
	)
	(footprint ""
		(layer "F.Cu")
		(at 196.708014 -78.42377 180)
		(property "Reference" "R1352"
			(at 0 0 180)
			(layer "F.SilkS")
			(hide yes)
			(effects
				(font
					(size 1.27 1.27)
				)
			)
		)
		(property "Value" ""
			(at 0 0 180)
			(layer "F.Fab")
			(effects
				(font
					(size 1.27 1.27)
				)
			)
		)
		(duplicate_pad_numbers_are_jumpers no)
		(fp_line
			(start 0.7874 0.4064)
			(end -0.7874 0.4064)
			(stroke
				(width 0.1524)
				(type default)
			)
			(layer "F.SilkS")
		)
		(fp_line
			(start 0.7874 -0.4064)
			(end 0.7874 0.4064)
			(stroke
				(width 0.1524)
				(type default)
			)
			(layer "F.SilkS")
		)
		(fp_line
			(start -0.7874 0.4064)
			(end -0.7874 -0.4064)
			(stroke
				(width 0.1524)
				(type default)
			)
			(layer "F.SilkS")
		)
		(fp_line
			(start -0.7874 -0.4064)
			(end 0.7874 -0.4064)
			(stroke
				(width 0.1524)
				(type default)
			)
			(layer "F.SilkS")
		)
		(fp_line
			(start 0.67945 0.3048)
			(end 0.120396 0.3048)
			(stroke
				(width 0.1)
				(type default)
			)
			(layer "F.Fab")
		)
		(fp_line
			(start 0.67945 -0.3048)
			(end 0.67945 0.3048)
			(stroke
				(width 0.1)
				(type default)
			)
			(layer "F.Fab")
		)
		(fp_line
			(start 0.12065 -0.2794)
			(end 0.12065 -0.3048)
			(stroke
				(width 0.1)
				(type default)
			)
			(layer "F.Fab")
		)
		(fp_line
			(start 0.12065 -0.3048)
			(end 0.67945 -0.3048)
			(stroke
				(width 0.1)
				(type default)
			)
			(layer "F.Fab")
		)
		(fp_line
			(start 0.120396 0.3048)
			(end 0.120396 0.2794)
			(stroke
				(width 0.1)
				(type default)
			)
			(layer "F.Fab")
		)
		(fp_line
			(start 0.120396 0.2794)
			(end -0.12065 0.2794)
			(stroke
				(width 0.1)
				(type default)
			)
			(layer "F.Fab")
		)
		(fp_line
			(start -0.12065 0.3048)
			(end -0.67945 0.3048)
			(stroke
				(width 0.1)
				(type default)
			)
			(layer "F.Fab")
		)
		(fp_line
			(start -0.12065 0.2794)
			(end -0.12065 0.3048)
			(stroke
				(width 0.1)
				(type default)
			)
			(layer "F.Fab")
		)
		(fp_line
			(start -0.12065 -0.2794)
			(end 0.12065 -0.2794)
			(stroke
				(width 0.1)
				(type default)
			)
			(layer "F.Fab")
		)
		(fp_line
			(start -0.12065 -0.305054)
			(end -0.12065 -0.2794)
			(stroke
				(width 0.1)
				(type default)
			)
			(layer "F.Fab")
		)
		(fp_line
			(start -0.67945 0.3048)
			(end -0.67945 -0.305054)
			(stroke
				(width 0.1)
				(type default)
			)
			(layer "F.Fab")
		)
		(fp_line
			(start -0.67945 -0.305054)
			(end -0.12065 -0.305054)
			(stroke
				(width 0.1)
				(type default)
			)
			(layer "F.Fab")
		)
		(pad "1" smd circle
			(at -0.40005 0 180)
			(size 0 0)
			(layers "F.Cu" "F.Mask" "F.Paste")
			(net "RMII_OCP_BMC_RXD_1")
		)
		(pad "2" smd circle
			(at 0.40005 0 180)
			(size 0 0)
			(layers "F.Cu" "F.Mask" "F.Paste")
			(net "GND")
		)
	)
	(footprint ""
		(layer "F.Cu")
		(at 220.100652 -103.330248)
		(property "Reference" "R2330"
			(at 0 0 0)
			(layer "F.SilkS")
			(hide yes)
			(effects
				(font
					(size 1.27 1.27)
				)
			)
		)
		(property "Value" ""
			(at 0 0 0)
			(layer "F.Fab")
			(effects
				(font
					(size 1.27 1.27)
				)
			)
		)
		(duplicate_pad_numbers_are_jumpers no)
		(fp_line
			(start -0.7874 -0.4064)
			(end 0.7874 -0.4064)
			(stroke
				(width 0.1524)
				(type default)
			)
			(layer "F.SilkS")
		)
		(fp_line
			(start -0.7874 0.4064)
			(end -0.7874 -0.4064)
			(stroke
				(width 0.1524)
				(type default)
			)
			(layer "F.SilkS")
		)
		(fp_line
			(start 0.7874 -0.4064)
			(end 0.7874 0.4064)
			(stroke
				(width 0.1524)
				(type default)
			)
			(layer "F.SilkS")
		)
		(fp_line
			(start 0.7874 0.4064)
			(end -0.7874 0.4064)
			(stroke
				(width 0.1524)
				(type default)
			)
			(layer "F.SilkS")
		)
		(fp_line
			(start -0.67945 -0.305054)
			(end -0.12065 -0.305054)
			(stroke
				(width 0.1)
				(type default)
			)
			(layer "F.Fab")
		)
		(fp_line
			(start -0.67945 0.3048)
			(end -0.67945 -0.305054)
			(stroke
				(width 0.1)
				(type default)
			)
			(layer "F.Fab")
		)
		(fp_line
			(start -0.12065 -0.305054)
			(end -0.12065 -0.2794)
			(stroke
				(width 0.1)
				(type default)
			)
			(layer "F.Fab")
		)
		(fp_line
			(start -0.12065 -0.2794)
			(end 0.12065 -0.2794)
			(stroke
				(width 0.1)
				(type default)
			)
			(layer "F.Fab")
		)
		(fp_line
			(start -0.12065 0.2794)
			(end -0.12065 0.3048)
			(stroke
				(width 0.1)
				(type default)
			)
			(layer "F.Fab")
		)
		(fp_line
			(start -0.12065 0.3048)
			(end -0.67945 0.3048)
			(stroke
				(width 0.1)
				(type default)
			)
			(layer "F.Fab")
		)
		(fp_line
			(start 0.120396 0.2794)
			(end -0.12065 0.2794)
			(stroke
				(width 0.1)
				(type default)
			)
			(layer "F.Fab")
		)
		(fp_line
			(start 0.120396 0.3048)
			(end 0.120396 0.2794)
			(stroke
				(width 0.1)
				(type default)
			)
			(layer "F.Fab")
		)
		(fp_line
			(start 0.12065 -0.3048)
			(end 0.67945 -0.3048)
			(stroke
				(width 0.1)
				(type default)
			)
			(layer "F.Fab")
		)
		(fp_line
			(start 0.12065 -0.2794)
			(end 0.12065 -0.3048)
			(stroke
				(width 0.1)
				(type default)
			)
			(layer "F.Fab")
		)
		(fp_line
			(start 0.67945 -0.3048)
			(end 0.67945 0.3048)
			(stroke
				(width 0.1)
				(type default)
			)
			(layer "F.Fab")
		)
		(fp_line
			(start 0.67945 0.3048)
			(end 0.120396 0.3048)
			(stroke
				(width 0.1)
				(type default)
			)
			(layer "F.Fab")
		)
		(pad "1" smd circle
			(at -0.40005 0)
			(size 0 0)
			(layers "F.Cu" "F.Mask" "F.Paste")
			(net "PWRGD_DSW_PWROK_R4")
		)
		(pad "2" smd circle
			(at 0.40005 0)
			(size 0 0)
			(layers "F.Cu" "F.Mask" "F.Paste")
			(net "PWRGD_DSW_PWROK")
		)
	)
	(footprint ""
		(layer "F.Cu")
		(at 367.920778 -417.15055 90)
		(property "Reference" "R4208"
			(at 0 0 90)
			(layer "F.SilkS")
			(hide yes)
			(effects
				(font
					(size 1.27 1.27)
				)
			)
		)
		(property "Value" ""
			(at 0 0 90)
			(layer "F.Fab")
			(effects
				(font
					(size 1.27 1.27)
				)
			)
		)
		(duplicate_pad_numbers_are_jumpers no)
		(fp_line
			(start 0.7874 -0.4064)
			(end 0.7874 0.4064)
			(stroke
				(width 0.1524)
				(type default)
			)
			(layer "F.SilkS")
		)
		(fp_line
			(start -0.7874 -0.4064)
			(end 0.7874 -0.4064)
			(stroke
				(width 0.1524)
				(type default)
			)
			(layer "F.SilkS")
		)
		(fp_line
			(start 0.7874 0.4064)
			(end -0.7874 0.4064)
			(stroke
				(width 0.1524)
				(type default)
			)
			(layer "F.SilkS")
		)
		(fp_line
			(start -0.7874 0.4064)
			(end -0.7874 -0.4064)
			(stroke
				(width 0.1524)
				(type default)
			)
			(layer "F.SilkS")
		)
		(fp_line
			(start -0.12065 -0.305054)
			(end -0.12065 -0.2794)
			(stroke
				(width 0.1)
				(type default)
			)
			(layer "F.Fab")
		)
		(fp_line
			(start -0.67945 -0.305054)
			(end -0.12065 -0.305054)
			(stroke
				(width 0.1)
				(type default)
			)
			(layer "F.Fab")
		)
		(fp_line
			(start 0.67945 -0.3048)
			(end 0.67945 0.3048)
			(stroke
				(width 0.1)
				(type default)
			)
			(layer "F.Fab")
		)
		(fp_line
			(start 0.12065 -0.3048)
			(end 0.67945 -0.3048)
			(stroke
				(width 0.1)
				(type default)
			)
			(layer "F.Fab")
		)
		(fp_line
			(start 0.12065 -0.2794)
			(end 0.12065 -0.3048)
			(stroke
				(width 0.1)
				(type default)
			)
			(layer "F.Fab")
		)
		(fp_line
			(start -0.12065 -0.2794)
			(end 0.12065 -0.2794)
			(stroke
				(width 0.1)
				(type default)
			)
			(layer "F.Fab")
		)
		(fp_line
			(start 0.120396 0.2794)
			(end -0.12065 0.2794)
			(stroke
				(width 0.1)
				(type default)
			)
			(layer "F.Fab")
		)
		(fp_line
			(start -0.12065 0.2794)
			(end -0.12065 0.3048)
			(stroke
				(width 0.1)
				(type default)
			)
			(layer "F.Fab")
		)
		(fp_line
			(start 0.67945 0.3048)
			(end 0.120396 0.3048)
			(stroke
				(width 0.1)
				(type default)
			)
			(layer "F.Fab")
		)
		(fp_line
			(start 0.120396 0.3048)
			(end 0.120396 0.2794)
			(stroke
				(width 0.1)
				(type default)
			)
			(layer "F.Fab")
		)
		(fp_line
			(start -0.12065 0.3048)
			(end -0.67945 0.3048)
			(stroke
				(width 0.1)
				(type default)
			)
			(layer "F.Fab")
		)
		(fp_line
			(start -0.67945 0.3048)
			(end -0.67945 -0.305054)
			(stroke
				(width 0.1)
				(type default)
			)
			(layer "F.Fab")
		)
		(pad "1" smd circle
			(at -0.40005 0 90)
			(size 0 0)
			(layers "F.Cu" "F.Mask" "F.Paste")
			(net "P3V3_AUX")
		)
		(pad "2" smd circle
			(at 0.40005 0 90)
			(size 0 0)
			(layers "F.Cu" "F.Mask" "F.Paste")
			(net "FM_THERMAL_ALERT_N")
		)
	)
	(footprint ""
		(layer "F.Cu")
		(at 131.579874 -408.517344 -90)
		(property "Reference" "C1523"
			(at 0 0 270)
			(layer "F.SilkS")
			(hide yes)
			(effects
				(font
					(size 1.27 1.27)
				)
			)
		)
		(property "Value" ""
			(at 0 0 270)
			(layer "F.Fab")
			(effects
				(font
					(size 1.27 1.27)
				)
			)
		)
		(duplicate_pad_numbers_are_jumpers no)
		(fp_line
			(start -0.299974 0.150114)
			(end -0.299974 -0.150114)
			(stroke
				(width 0.1)
				(type default)
			)
			(layer "F.Fab")
		)
		(fp_line
			(start 0.299974 0.150114)
			(end -0.299974 0.150114)
			(stroke
				(width 0.1)
				(type default)
			)
			(layer "F.Fab")
		)
		(fp_line
			(start -0.299974 -0.150114)
			(end 0.299974 -0.150114)
			(stroke
				(width 0.1)
				(type default)
			)
			(layer "F.Fab")
		)
		(fp_line
			(start 0.299974 -0.150114)
			(end 0.299974 0.150114)
			(stroke
				(width 0.1)
				(type default)
			)
			(layer "F.Fab")
		)
		(pad "1" smd rect
			(at -0.2667 0 270)
			(size 0.3048 0.381)
			(layers "F.Cu" "F.Mask" "F.Paste")
			(net "P5E_CPU1_PE3_TX_C_DP<12>")
		)
		(pad "2" smd rect
			(at 0.2667 0 270)
			(size 0.3048 0.381)
			(layers "F.Cu" "F.Mask" "F.Paste")
			(net "P5E_CPU1_PE3_TX_DP<12>")
		)
	)
	(footprint ""
		(layer "F.Cu")
		(at 448.799966 -435.59984)
		(property "Reference" "H90"
			(at -3.91922 -2.705608 0)
			(unlocked yes)
			(layer "F.SilkS")
			(effects
				(font
					(size 0.7874 0.5842)
					(thickness 0.1524)
				)
				(justify left)
			)
		)
		(property "Value" ""
			(at 0 0 0)
			(layer "F.Fab")
			(effects
				(font
					(size 1.27 1.27)
				)
			)
		)
		(duplicate_pad_numbers_are_jumpers no)
		(fp_circle
			(center 0 0)
			(end 2.6289 0)
			(stroke
				(width 0.1524)
				(type default)
			)
			(fill no)
			(layer "F.SilkS")
		)
		(fp_circle
			(center 0 0)
			(end 2.6289 0)
			(stroke
				(width 0.1524)
				(type default)
			)
			(fill no)
			(layer "B.SilkS")
		)
		(fp_circle
			(center 0 0)
			(end 2.6289 0)
			(stroke
				(width 0.1)
				(type default)
			)
			(fill no)
			(layer "B.Fab")
		)
		(fp_circle
			(center 0 0)
			(end 2.6289 0)
			(stroke
				(width 0.1)
				(type default)
			)
			(fill no)
			(layer "F.Fab")
		)
		(pad "" np_thru_hole circle
			(at 0 0)
			(size 3.0988 3.0988)
			(drill 3.0988)
			(layers "*.Cu" "*.Mask")
			(clearance 0.254)
			(thermal_gap 0.254)
		)
	)
	(footprint ""
		(layer "F.Cu")
		(at 76.437998 -402.371052 -90)
		(property "Reference" "C729"
			(at 0 0 270)
			(layer "F.SilkS")
			(hide yes)
			(effects
				(font
					(size 1.27 1.27)
				)
			)
		)
		(property "Value" ""
			(at 0 0 270)
			(layer "F.Fab")
			(effects
				(font
					(size 1.27 1.27)
				)
			)
		)
		(duplicate_pad_numbers_are_jumpers no)
		(fp_line
			(start -0.299974 0.150114)
			(end -0.299974 -0.150114)
			(stroke
				(width 0.1)
				(type default)
			)
			(layer "F.Fab")
		)
		(fp_line
			(start 0.299974 0.150114)
			(end -0.299974 0.150114)
			(stroke
				(width 0.1)
				(type default)
			)
			(layer "F.Fab")
		)
		(fp_line
			(start -0.299974 -0.150114)
			(end 0.299974 -0.150114)
			(stroke
				(width 0.1)
				(type default)
			)
			(layer "F.Fab")
		)
		(fp_line
			(start 0.299974 -0.150114)
			(end 0.299974 0.150114)
			(stroke
				(width 0.1)
				(type default)
			)
			(layer "F.Fab")
		)
		(pad "1" smd rect
			(at -0.2667 0 270)
			(size 0.3048 0.381)
			(layers "F.Cu" "F.Mask" "F.Paste")
			(net "P5E_CPU1_PE0_TX_C_DP<6>")
		)
		(pad "2" smd rect
			(at 0.2667 0 270)
			(size 0.3048 0.381)
			(layers "F.Cu" "F.Mask" "F.Paste")
			(net "P5E_CPU1_PE0_TX_DP<6>")
		)
	)
)
